(kicad_pcb
	(version 20260206)
	(generator "pcbnew")
	(generator_version "10.0")
	(general
		(thickness 1.6)
		(legacy_teardrops no)
	)
	(paper "A4")
	(title_block
		(title "04192023_DAF0TMB3IC0_F0TG_MB_C_brd_V02_OCP.brd")
		(comment 1 "Grand Teton / footprint 2783 of 8354 (U26), pads 3781-3891 of 6102")
	)
	(layers
		(0 "F.Cu" signal "TOP")
		(4 "In1.Cu" signal "GND")
		(6 "In2.Cu" signal "IN1")
		(8 "In3.Cu" signal "GND1")
		(10 "In4.Cu" signal "IN2")
		(12 "In5.Cu" signal "GND2")
		(14 "In6.Cu" signal "IN3")
		(16 "In7.Cu" signal "GND3")
		(18 "In8.Cu" signal "VCC")
		(20 "In9.Cu" signal "VCC1")
		(22 "In10.Cu" signal "GND4")
		(24 "In11.Cu" signal "IN4")
		(26 "In12.Cu" signal "GND5")
		(28 "In13.Cu" signal "IN5")
		(30 "In14.Cu" signal "GND6")
		(32 "In15.Cu" signal "IN6")
		(34 "In16.Cu" signal "GND7")
		(2 "B.Cu" signal "BOTTOM")
		(9 "F.Adhes" user "F.Adhesive")
		(11 "B.Adhes" user "B.Adhesive")
		(13 "F.Paste" user "Package Geometry/Pastemask Top")
		(15 "B.Paste" user "Package Geometry/Pastemask Bottom")
		(5 "F.SilkS" user "Ref Des/Silkscreen Top")
		(7 "B.SilkS" user "Ref Des/Silkscreen Bottom")
		(1 "F.Mask" user "Board Geometry/Soldermask Top")
		(3 "B.Mask" user "Board Geometry/Soldermask Bottom")
		(17 "Dwgs.User" user "User.Drawings")
		(19 "Cmts.User" user "User.Comments")
		(21 "Eco1.User" user "User.Eco1")
		(23 "Eco2.User" user "User.Eco2")
		(25 "Edge.Cuts" user "Board Geometry/Outline")
		(27 "Margin" user)
		(31 "F.CrtYd" user "Package Geometry/Place Bound Top")
		(29 "B.CrtYd" user "Package Geometry/Place Bound Bottom")
		(35 "F.Fab" user "Ref Des/Assembly Top")
		(33 "B.Fab" user "Ref Des/Assembly Bottom")
	)
	(footprint ""
		(layer "F.Cu")
		(at 111.927894 -258.880356 180)
		(property "Reference" "U26"
			(at -45.05579 -61.794136 0)
			(unlocked yes)
			(layer "F.SilkS")
			(effects
				(font
					(size 0.7874 0.5842)
					(thickness 0.1524)
				)
			)
		)
		(property "Value" ""
			(at 0 0 180)
			(layer "F.Fab")
			(effects
				(font
					(size 1.27 1.27)
				)
			)
		)
		(duplicate_pad_numbers_are_jumpers no)
		(pad "CP39" smd circle
			(at 0.78994 24.660098 180)
			(size 0.450088 0.450088)
			(layers "F.Cu" "F.Mask" "F.Paste")
			(net "GND")
		)
		(pad "CP40" smd circle
			(at 1.729994 24.660098 180)
			(size 0.450088 0.450088)
			(layers "F.Cu" "F.Mask" "F.Paste")
			(net "P5E_CPU1_P0_TX_DN<14>")
		)
		(pad "CP41" smd circle
			(at 2.670048 24.660098 180)
			(size 0.450088 0.450088)
			(layers "F.Cu" "F.Mask" "F.Paste")
			(net "P5E_CPU1_P0_TX_DP<14>")
		)
		(pad "CP42" smd circle
			(at 3.610102 24.660098 180)
			(size 0.450088 0.450088)
			(layers "F.Cu" "F.Mask" "F.Paste")
			(net "GND")
		)
		(pad "CP43" smd circle
			(at 4.549902 24.660098 180)
			(size 0.450088 0.450088)
			(layers "F.Cu" "F.Mask" "F.Paste")
			(net "PVDDCR_CPU1_P1")
		)
		(pad "CP44" smd circle
			(at 5.489956 24.660098 180)
			(size 0.450088 0.450088)
			(layers "F.Cu" "F.Mask" "F.Paste")
			(net "PVDDCR_CPU1_P1")
		)
		(pad "CP45" smd circle
			(at 6.43001 24.660098 180)
			(size 0.450088 0.450088)
			(layers "F.Cu" "F.Mask" "F.Paste")
			(net "GND")
		)
		(pad "CP46" smd circle
			(at 7.370064 24.660098 180)
			(size 0.450088 0.450088)
			(layers "F.Cu" "F.Mask" "F.Paste")
			(net "PVDDCR_CPU1_P1")
		)
		(pad "CP47" smd circle
			(at 8.310118 24.660098 180)
			(size 0.450088 0.450088)
			(layers "F.Cu" "F.Mask" "F.Paste")
			(net "PVDDCR_CPU1_P1")
		)
		(pad "CP48" smd circle
			(at 9.249918 24.660098 180)
			(size 0.450088 0.450088)
			(layers "F.Cu" "F.Mask" "F.Paste")
			(net "GND")
		)
		(pad "CP49" smd circle
			(at 10.189972 24.660098 180)
			(size 0.450088 0.450088)
			(layers "F.Cu" "F.Mask" "F.Paste")
			(net "PVDDCR_CPU1_P1")
		)
		(pad "CP50" smd circle
			(at 11.130026 24.660098 180)
			(size 0.450088 0.450088)
			(layers "F.Cu" "F.Mask" "F.Paste")
			(net "PVDDCR_CPU1_P1")
		)
		(pad "CP51" smd circle
			(at 12.07008 24.660098 180)
			(size 0.450088 0.450088)
			(layers "F.Cu" "F.Mask" "F.Paste")
			(net "GND")
		)
		(pad "CP52" smd circle
			(at 13.00988 24.660098 180)
			(size 0.450088 0.450088)
			(layers "F.Cu" "F.Mask" "F.Paste")
			(net "PVDDCR_CPU1_P1")
		)
		(pad "CP53" smd circle
			(at 13.949934 24.660098 180)
			(size 0.450088 0.450088)
			(layers "F.Cu" "F.Mask" "F.Paste")
			(net "PVDDCR_CPU1_P1")
		)
		(pad "CP54" smd circle
			(at 14.889988 24.660098 180)
			(size 0.450088 0.450088)
			(layers "F.Cu" "F.Mask" "F.Paste")
			(net "GND")
		)
		(pad "CP55" smd circle
			(at 15.830042 24.660098 180)
			(size 0.450088 0.450088)
			(layers "F.Cu" "F.Mask" "F.Paste")
			(net "M_C_CPU1_SB_DQ<15>")
		)
		(pad "CP56" smd circle
			(at 16.770096 24.660098 180)
			(size 0.450088 0.450088)
			(layers "F.Cu" "F.Mask" "F.Paste")
			(net "M_C_CPU1_SB_DQ<16>")
		)
		(pad "CP57" smd circle
			(at 17.709896 24.660098 180)
			(size 0.450088 0.450088)
			(layers "F.Cu" "F.Mask" "F.Paste")
			(net "GND")
		)
		(pad "CP58" smd circle
			(at 18.64995 24.660098 180)
			(size 0.450088 0.450088)
			(layers "F.Cu" "F.Mask" "F.Paste")
			(net "M_D_CPU1_SB_DQ<15>")
		)
		(pad "CP59" smd circle
			(at 19.590004 24.660098 180)
			(size 0.450088 0.450088)
			(layers "F.Cu" "F.Mask" "F.Paste")
			(net "GND")
		)
		(pad "CP60" smd circle
			(at 20.530058 24.660098 180)
			(size 0.450088 0.450088)
			(layers "F.Cu" "F.Mask" "F.Paste")
			(net "M_D_CPU1_SB_DQ<16>")
		)
		(pad "CP61" smd circle
			(at 21.470112 24.660098 180)
			(size 0.450088 0.450088)
			(layers "F.Cu" "F.Mask" "F.Paste")
			(net "GND")
		)
		(pad "CP62" smd circle
			(at 22.409912 24.660098 180)
			(size 0.450088 0.450088)
			(layers "F.Cu" "F.Mask" "F.Paste")
			(net "M_B_CPU1_SB_DQ<15>")
		)
		(pad "CP63" smd circle
			(at 23.349966 24.660098 180)
			(size 0.450088 0.450088)
			(layers "F.Cu" "F.Mask" "F.Paste")
			(net "M_B_CPU1_SB_DQ<16>")
		)
		(pad "CP64" smd circle
			(at 24.29002 24.660098 180)
			(size 0.450088 0.450088)
			(layers "F.Cu" "F.Mask" "F.Paste")
			(net "GND")
		)
		(pad "CP65" smd circle
			(at 25.230074 24.660098 180)
			(size 0.450088 0.450088)
			(layers "F.Cu" "F.Mask" "F.Paste")
			(net "M_F_CPU1_SB_DQ<15>")
		)
		(pad "CP66" smd circle
			(at 26.170128 24.660098 180)
			(size 0.450088 0.450088)
			(layers "F.Cu" "F.Mask" "F.Paste")
			(net "GND")
		)
		(pad "CP67" smd circle
			(at 27.109928 24.660098 180)
			(size 0.450088 0.450088)
			(layers "F.Cu" "F.Mask" "F.Paste")
			(net "M_F_CPU1_SB_DQ<16>")
		)
		(pad "CP68" smd circle
			(at 28.049982 24.660098 180)
			(size 0.450088 0.450088)
			(layers "F.Cu" "F.Mask" "F.Paste")
			(net "GND")
		)
		(pad "CP69" smd circle
			(at 28.990036 24.660098 180)
			(size 0.450088 0.450088)
			(layers "F.Cu" "F.Mask" "F.Paste")
			(net "M_E_CPU1_SB_DQ<15>")
		)
		(pad "CP70" smd circle
			(at 29.93009 24.660098 180)
			(size 0.450088 0.450088)
			(layers "F.Cu" "F.Mask" "F.Paste")
			(net "M_E_CPU1_SB_DQ<16>")
		)
		(pad "CP71" smd circle
			(at 30.86989 24.660098 180)
			(size 0.450088 0.450088)
			(layers "F.Cu" "F.Mask" "F.Paste")
			(net "GND")
		)
		(pad "CP72" smd circle
			(at 31.809944 24.660098 180)
			(size 0.450088 0.450088)
			(layers "F.Cu" "F.Mask" "F.Paste")
			(net "M_A_CPU1_SB_DQ<15>")
		)
		(pad "CP73" smd circle
			(at 32.749998 24.660098 180)
			(size 0.450088 0.450088)
			(layers "F.Cu" "F.Mask" "F.Paste")
			(net "GND")
		)
		(pad "CP74" smd circle
			(at 33.690052 24.660098 180)
			(size 0.450088 0.450088)
			(layers "F.Cu" "F.Mask" "F.Paste")
			(net "M_A_CPU1_SB_DQ<16>")
		)
		(pad "CR1" smd circle
			(at -34.459926 25.470104 180)
			(size 0.450088 0.450088)
			(layers "F.Cu" "F.Mask" "F.Paste")
			(net "GND")
		)
		(pad "CR2" smd circle
			(at -33.519872 25.470104 180)
			(size 0.450088 0.450088)
			(layers "F.Cu" "F.Mask" "F.Paste")
			(net "M_G_CPU1_SB_DQ<18>")
		)
		(pad "CR3" smd circle
			(at -32.580072 25.470104 180)
			(size 0.450088 0.450088)
			(layers "F.Cu" "F.Mask" "F.Paste")
			(net "M_G_CPU1_SB_DQ<17>")
		)
		(pad "CR4" smd circle
			(at -31.640018 25.470104 180)
			(size 0.450088 0.450088)
			(layers "F.Cu" "F.Mask" "F.Paste")
			(net "GND")
		)
		(pad "CR5" smd circle
			(at -30.699964 25.470104 180)
			(size 0.450088 0.450088)
			(layers "F.Cu" "F.Mask" "F.Paste")
			(net "M_K_CPU1_SB_DQ<18>")
		)
		(pad "CR6" smd circle
			(at -29.75991 25.470104 180)
			(size 0.450088 0.450088)
			(layers "F.Cu" "F.Mask" "F.Paste")
			(net "GND")
		)
		(pad "CR7" smd circle
			(at -28.82011 25.470104 180)
			(size 0.450088 0.450088)
			(layers "F.Cu" "F.Mask" "F.Paste")
			(net "M_K_CPU1_SB_DQ<17>")
		)
		(pad "CR8" smd circle
			(at -27.880056 25.470104 180)
			(size 0.450088 0.450088)
			(layers "F.Cu" "F.Mask" "F.Paste")
			(net "GND")
		)
		(pad "CR9" smd circle
			(at -26.940002 25.470104 180)
			(size 0.450088 0.450088)
			(layers "F.Cu" "F.Mask" "F.Paste")
			(net "M_L_CPU1_SB_DQ<18>")
		)
		(pad "CR10" smd circle
			(at -25.999948 25.470104 180)
			(size 0.450088 0.450088)
			(layers "F.Cu" "F.Mask" "F.Paste")
			(net "M_L_CPU1_SB_DQ<17>")
		)
		(pad "CR11" smd circle
			(at -25.059894 25.470104 180)
			(size 0.450088 0.450088)
			(layers "F.Cu" "F.Mask" "F.Paste")
			(net "GND")
		)
		(pad "CR12" smd circle
			(at -24.120094 25.470104 180)
			(size 0.450088 0.450088)
			(layers "F.Cu" "F.Mask" "F.Paste")
			(net "M_H_CPU1_SB_DQ<18>")
		)
		(pad "CR13" smd circle
			(at -23.18004 25.470104 180)
			(size 0.450088 0.450088)
			(layers "F.Cu" "F.Mask" "F.Paste")
			(net "GND")
		)
		(pad "CR14" smd circle
			(at -22.239986 25.470104 180)
			(size 0.450088 0.450088)
			(layers "F.Cu" "F.Mask" "F.Paste")
			(net "M_H_CPU1_SB_DQ<17>")
		)
		(pad "CR15" smd circle
			(at -21.299932 25.470104 180)
			(size 0.450088 0.450088)
			(layers "F.Cu" "F.Mask" "F.Paste")
			(net "GND")
		)
		(pad "CR16" smd circle
			(at -20.359878 25.470104 180)
			(size 0.450088 0.450088)
			(layers "F.Cu" "F.Mask" "F.Paste")
			(net "M_J_CPU1_SB_DQ<18>")
		)
		(pad "CR17" smd circle
			(at -19.420078 25.470104 180)
			(size 0.450088 0.450088)
			(layers "F.Cu" "F.Mask" "F.Paste")
			(net "M_J_CPU1_SB_DQ<17>")
		)
		(pad "CR18" smd circle
			(at -18.480024 25.470104 180)
			(size 0.450088 0.450088)
			(layers "F.Cu" "F.Mask" "F.Paste")
			(net "GND")
		)
		(pad "CR19" smd circle
			(at -17.53997 25.470104 180)
			(size 0.450088 0.450088)
			(layers "F.Cu" "F.Mask" "F.Paste")
			(net "M_I_CPU1_SB_DQ<18>")
		)
		(pad "CR20" smd circle
			(at -16.599916 25.470104 180)
			(size 0.450088 0.450088)
			(layers "F.Cu" "F.Mask" "F.Paste")
			(net "GND")
		)
		(pad "CR21" smd circle
			(at -15.660116 25.470104 180)
			(size 0.450088 0.450088)
			(layers "F.Cu" "F.Mask" "F.Paste")
			(net "M_I_CPU1_SB_DQ<17>")
		)
		(pad "CR22" smd circle
			(at -14.720062 25.470104 180)
			(size 0.450088 0.450088)
			(layers "F.Cu" "F.Mask" "F.Paste")
			(net "GND")
		)
		(pad "CR23" smd circle
			(at -13.780008 25.470104 180)
			(size 0.450088 0.450088)
			(layers "F.Cu" "F.Mask" "F.Paste")
			(net "P5E_CPU1_P2_RX_DP<14>")
		)
		(pad "CR24" smd circle
			(at -12.839954 25.470104 180)
			(size 0.450088 0.450088)
			(layers "F.Cu" "F.Mask" "F.Paste")
			(net "P5E_CPU1_P2_RX_DN<14>")
		)
		(pad "CR25" smd circle
			(at -11.8999 25.470104 180)
			(size 0.450088 0.450088)
			(layers "F.Cu" "F.Mask" "F.Paste")
			(net "GND")
		)
		(pad "CR26" smd circle
			(at -10.9601 25.470104 180)
			(size 0.450088 0.450088)
			(layers "F.Cu" "F.Mask" "F.Paste")
			(net "P5E_CPU1_P2_RX_DP<11>")
		)
		(pad "CR27" smd circle
			(at -10.020046 25.470104 180)
			(size 0.450088 0.450088)
			(layers "F.Cu" "F.Mask" "F.Paste")
			(net "P5E_CPU1_P2_RX_DN<11>")
		)
		(pad "CR28" smd circle
			(at -9.079992 25.470104 180)
			(size 0.450088 0.450088)
			(layers "F.Cu" "F.Mask" "F.Paste")
			(net "GND")
		)
		(pad "CR29" smd circle
			(at -8.139938 25.470104 180)
			(size 0.450088 0.450088)
			(layers "F.Cu" "F.Mask" "F.Paste")
			(net "P5E_CPU1_P2_RX_DP<8>")
		)
		(pad "CR30" smd circle
			(at -7.199884 25.470104 180)
			(size 0.450088 0.450088)
			(layers "F.Cu" "F.Mask" "F.Paste")
			(net "P5E_CPU1_P2_RX_DN<8>")
		)
		(pad "CR31" smd circle
			(at -6.260084 25.470104 180)
			(size 0.450088 0.450088)
			(layers "F.Cu" "F.Mask" "F.Paste")
			(net "GND")
		)
		(pad "CR32" smd circle
			(at -5.32003 25.470104 180)
			(size 0.450088 0.450088)
			(layers "F.Cu" "F.Mask" "F.Paste")
			(net "P5E_CPU1_P2_RX_DP<5>")
		)
		(pad "CR33" smd circle
			(at -4.379976 25.470104 180)
			(size 0.450088 0.450088)
			(layers "F.Cu" "F.Mask" "F.Paste")
			(net "P5E_CPU1_P2_RX_DN<5>")
		)
		(pad "CR34" smd circle
			(at -3.439922 25.470104 180)
			(size 0.450088 0.450088)
			(layers "F.Cu" "F.Mask" "F.Paste")
			(net "GND")
		)
		(pad "CR35" smd circle
			(at -2.500122 25.470104 180)
			(size 0.450088 0.450088)
			(layers "F.Cu" "F.Mask" "F.Paste")
			(net "GND")
		)
		(pad "CR36" smd circle
			(at -1.560068 25.470104 180)
			(size 0.450088 0.450088)
			(layers "F.Cu" "F.Mask" "F.Paste")
			(net "GND")
		)
		(pad "CR40" smd circle
			(at 1.260094 25.470104 180)
			(size 0.450088 0.450088)
			(layers "F.Cu" "F.Mask" "F.Paste")
			(net "GND")
		)
		(pad "CR41" smd circle
			(at 2.199894 25.470104 180)
			(size 0.450088 0.450088)
			(layers "F.Cu" "F.Mask" "F.Paste")
			(net "GND")
		)
		(pad "CR42" smd circle
			(at 3.139948 25.470104 180)
			(size 0.450088 0.450088)
			(layers "F.Cu" "F.Mask" "F.Paste")
			(net "GND")
		)
		(pad "CR43" smd circle
			(at 4.080002 25.470104 180)
			(size 0.450088 0.450088)
			(layers "F.Cu" "F.Mask" "F.Paste")
			(net "P5E_CPU1_P0_TX_DN<10>")
		)
		(pad "CR44" smd circle
			(at 5.020056 25.470104 180)
			(size 0.450088 0.450088)
			(layers "F.Cu" "F.Mask" "F.Paste")
			(net "P5E_CPU1_P0_TX_DP<10>")
		)
		(pad "CR45" smd circle
			(at 5.96011 25.470104 180)
			(size 0.450088 0.450088)
			(layers "F.Cu" "F.Mask" "F.Paste")
			(net "GND")
		)
		(pad "CR46" smd circle
			(at 6.89991 25.470104 180)
			(size 0.450088 0.450088)
			(layers "F.Cu" "F.Mask" "F.Paste")
			(net "P5E_CPU1_P0_TX_DN<7>")
		)
		(pad "CR47" smd circle
			(at 7.839964 25.470104 180)
			(size 0.450088 0.450088)
			(layers "F.Cu" "F.Mask" "F.Paste")
			(net "P5E_CPU1_P0_TX_DP<7>")
		)
		(pad "CR48" smd circle
			(at 8.780018 25.470104 180)
			(size 0.450088 0.450088)
			(layers "F.Cu" "F.Mask" "F.Paste")
			(net "GND")
		)
		(pad "CR49" smd circle
			(at 9.720072 25.470104 180)
			(size 0.450088 0.450088)
			(layers "F.Cu" "F.Mask" "F.Paste")
			(net "P5E_CPU1_P0_TX_DN<4>")
		)
		(pad "CR50" smd circle
			(at 10.659872 25.470104 180)
			(size 0.450088 0.450088)
			(layers "F.Cu" "F.Mask" "F.Paste")
			(net "P5E_CPU1_P0_TX_DP<4>")
		)
		(pad "CR51" smd circle
			(at 11.599926 25.470104 180)
			(size 0.450088 0.450088)
			(layers "F.Cu" "F.Mask" "F.Paste")
			(net "GND")
		)
		(pad "CR52" smd circle
			(at 12.53998 25.470104 180)
			(size 0.450088 0.450088)
			(layers "F.Cu" "F.Mask" "F.Paste")
			(net "P5E_CPU1_P0_TX_DN<1>")
		)
		(pad "CR53" smd circle
			(at 13.480034 25.470104 180)
			(size 0.450088 0.450088)
			(layers "F.Cu" "F.Mask" "F.Paste")
			(net "P5E_CPU1_P0_TX_DP<1>")
		)
		(pad "CR54" smd circle
			(at 14.420088 25.470104 180)
			(size 0.450088 0.450088)
			(layers "F.Cu" "F.Mask" "F.Paste")
			(net "GND")
		)
		(pad "CR55" smd circle
			(at 15.359888 25.470104 180)
			(size 0.450088 0.450088)
			(layers "F.Cu" "F.Mask" "F.Paste")
			(net "M_C_CPU1_SB_DQ<17>")
		)
		(pad "CR56" smd circle
			(at 16.299942 25.470104 180)
			(size 0.450088 0.450088)
			(layers "F.Cu" "F.Mask" "F.Paste")
			(net "GND")
		)
		(pad "CR57" smd circle
			(at 17.239996 25.470104 180)
			(size 0.450088 0.450088)
			(layers "F.Cu" "F.Mask" "F.Paste")
			(net "M_C_CPU1_SB_DQ<18>")
		)
		(pad "CR58" smd circle
			(at 18.18005 25.470104 180)
			(size 0.450088 0.450088)
			(layers "F.Cu" "F.Mask" "F.Paste")
			(net "GND")
		)
		(pad "CR59" smd circle
			(at 19.120104 25.470104 180)
			(size 0.450088 0.450088)
			(layers "F.Cu" "F.Mask" "F.Paste")
			(net "M_D_CPU1_SB_DQ<17>")
		)
		(pad "CR60" smd circle
			(at 20.059904 25.470104 180)
			(size 0.450088 0.450088)
			(layers "F.Cu" "F.Mask" "F.Paste")
			(net "M_D_CPU1_SB_DQ<18>")
		)
		(pad "CR61" smd circle
			(at 20.999958 25.470104 180)
			(size 0.450088 0.450088)
			(layers "F.Cu" "F.Mask" "F.Paste")
			(net "GND")
		)
		(pad "CR62" smd circle
			(at 21.940012 25.470104 180)
			(size 0.450088 0.450088)
			(layers "F.Cu" "F.Mask" "F.Paste")
			(net "M_B_CPU1_SB_DQ<17>")
		)
		(pad "CR63" smd circle
			(at 22.880066 25.470104 180)
			(size 0.450088 0.450088)
			(layers "F.Cu" "F.Mask" "F.Paste")
			(net "GND")
		)
		(pad "CR64" smd circle
			(at 23.82012 25.470104 180)
			(size 0.450088 0.450088)
			(layers "F.Cu" "F.Mask" "F.Paste")
			(net "M_B_CPU1_SB_DQ<18>")
		)
		(pad "CR65" smd circle
			(at 24.75992 25.470104 180)
			(size 0.450088 0.450088)
			(layers "F.Cu" "F.Mask" "F.Paste")
			(net "GND")
		)
		(pad "CR66" smd circle
			(at 25.699974 25.470104 180)
			(size 0.450088 0.450088)
			(layers "F.Cu" "F.Mask" "F.Paste")
			(net "M_F_CPU1_SB_DQ<17>")
		)
		(pad "CR67" smd circle
			(at 26.640028 25.470104 180)
			(size 0.450088 0.450088)
			(layers "F.Cu" "F.Mask" "F.Paste")
			(net "M_F_CPU1_SB_DQ<18>")
		)
		(pad "CR68" smd circle
			(at 27.580082 25.470104 180)
			(size 0.450088 0.450088)
			(layers "F.Cu" "F.Mask" "F.Paste")
			(net "GND")
		)
		(pad "CR69" smd circle
			(at 28.519882 25.470104 180)
			(size 0.450088 0.450088)
			(layers "F.Cu" "F.Mask" "F.Paste")
			(net "M_E_CPU1_SB_DQ<17>")
		)
		(pad "CR70" smd circle
			(at 29.459936 25.470104 180)
			(size 0.450088 0.450088)
			(layers "F.Cu" "F.Mask" "F.Paste")
			(net "GND")
		)
		(pad "CR71" smd circle
			(at 30.39999 25.470104 180)
			(size 0.450088 0.450088)
			(layers "F.Cu" "F.Mask" "F.Paste")
			(net "M_E_CPU1_SB_DQ<18>")
		)
		(pad "CR72" smd circle
			(at 31.340044 25.470104 180)
			(size 0.450088 0.450088)
			(layers "F.Cu" "F.Mask" "F.Paste")
			(net "GND")
		)
		(pad "CR73" smd circle
			(at 32.280098 25.470104 180)
			(size 0.450088 0.450088)
			(layers "F.Cu" "F.Mask" "F.Paste")
			(net "M_A_CPU1_SB_DQ<17>")
		)
		(pad "CR74" smd circle
			(at 33.219898 25.470104 180)
			(size 0.450088 0.450088)
			(layers "F.Cu" "F.Mask" "F.Paste")
			(net "M_A_CPU1_SB_DQ<18>")
		)
		(pad "CR75" smd circle
			(at 34.159952 25.470104 180)
			(size 0.450088 0.450088)
			(layers "F.Cu" "F.Mask" "F.Paste")
			(net "GND")
		)
		(pad "CT2" smd circle
			(at -33.990026 26.28011 180)
			(size 0.450088 0.450088)
			(layers "F.Cu" "F.Mask" "F.Paste")
			(net "M_G_CPU1_SB_DQS_DP<2>")
		)
		(pad "CT3" smd circle
			(at -33.049972 26.28011 180)
			(size 0.450088 0.450088)
			(layers "F.Cu" "F.Mask" "F.Paste")
			(net "GND")
		)
		(pad "CT4" smd circle
			(at -32.109918 26.28011 180)
			(size 0.450088 0.450088)
			(layers "F.Cu" "F.Mask" "F.Paste")
			(net "M_G_CPU1_SB_DQ<19>")
		)
	)
)
